(kicad_pcb
	(version 20260206)
	(generator "pcbnew")
	(generator_version "10.0")
	(general
		(thickness 1.6)
		(legacy_teardrops no)
	)
	(paper "A4")
	(title_block
		(title "04192023_DAF0TMB3IC0_F0TG_MB_C_brd_V02_OCP.brd")
		(comment 1 "Grand Teton / footprint 3721 of 8354 (J67), pads 1-113 of 291")
	)
	(layers
		(0 "F.Cu" signal "TOP")
		(4 "In1.Cu" signal "GND")
		(6 "In2.Cu" signal "IN1")
		(8 "In3.Cu" signal "GND1")
		(10 "In4.Cu" signal "IN2")
		(12 "In5.Cu" signal "GND2")
		(14 "In6.Cu" signal "IN3")
		(16 "In7.Cu" signal "GND3")
		(18 "In8.Cu" signal "VCC")
		(20 "In9.Cu" signal "VCC1")
		(22 "In10.Cu" signal "GND4")
		(24 "In11.Cu" signal "IN4")
		(26 "In12.Cu" signal "GND5")
		(28 "In13.Cu" signal "IN5")
		(30 "In14.Cu" signal "GND6")
		(32 "In15.Cu" signal "IN6")
		(34 "In16.Cu" signal "GND7")
		(2 "B.Cu" signal "BOTTOM")
		(9 "F.Adhes" user "F.Adhesive")
		(11 "B.Adhes" user "B.Adhesive")
		(13 "F.Paste" user "Package Geometry/Pastemask Top")
		(15 "B.Paste" user "Package Geometry/Pastemask Bottom")
		(5 "F.SilkS" user "Ref Des/Silkscreen Top")
		(7 "B.SilkS" user "Ref Des/Silkscreen Bottom")
		(1 "F.Mask" user "Board Geometry/Soldermask Top")
		(3 "B.Mask" user "Board Geometry/Soldermask Bottom")
		(17 "Dwgs.User" user "User.Drawings")
		(19 "Cmts.User" user "User.Comments")
		(21 "Eco1.User" user "User.Eco1")
		(23 "Eco2.User" user "User.Eco2")
		(25 "Edge.Cuts" user "Board Geometry/Outline")
		(27 "Margin" user)
		(31 "F.CrtYd" user "Package Geometry/Place Bound Top")
		(29 "B.CrtYd" user "Package Geometry/Place Bound Bottom")
		(35 "F.Fab" user "Ref Des/Assembly Top")
		(33 "B.Fab" user "Ref Des/Assembly Bottom")
	)
	(footprint ""
		(layer "F.Cu")
		(at 452.138034 -255.560068 180)
		(property "Reference" "J67"
			(at 2.380488 -81.709768 0)
			(unlocked yes)
			(layer "F.SilkS")
			(effects
				(font
					(size 0.7874 0.5842)
					(thickness 0.1524)
				)
			)
		)
		(property "Value" ""
			(at 0 0 180)
			(layer "F.Fab")
			(effects
				(font
					(size 1.27 1.27)
				)
			)
		)
		(duplicate_pad_numbers_are_jumpers no)
		(pad "1" smd rect
			(at -2.050034 -63.324994 90)
			(size 0.519938 1.4986)
			(layers "F.Cu" "F.Mask" "F.Paste")
			(net "P12V_MEM_CPU0")
		)
		(pad "2" smd rect
			(at -2.050034 -62.47511 90)
			(size 0.519938 1.4986)
			(layers "F.Cu" "F.Mask" "F.Paste")
			(net "Net_2403")
		)
		(pad "3" smd rect
			(at -2.050034 -61.624972 90)
			(size 0.519938 1.4986)
			(layers "F.Cu" "F.Mask" "F.Paste")
			(net "P3V3_AUX")
		)
		(pad "4" smd rect
			(at -2.050034 -60.775088 90)
			(size 0.519938 1.4986)
			(layers "F.Cu" "F.Mask" "F.Paste")
			(net "I3C_SPD_DDRL_CPU0_SCL")
		)
		(pad "5" smd rect
			(at -2.050034 -59.92495 90)
			(size 0.519938 1.4986)
			(layers "F.Cu" "F.Mask" "F.Paste")
			(net "I3C_SPD_DDRL_CPU0_SDA")
		)
		(pad "6" smd rect
			(at -2.050034 -59.075066 90)
			(size 0.519938 1.4986)
			(layers "F.Cu" "F.Mask" "F.Paste")
			(net "GND")
		)
		(pad "7" smd rect
			(at -2.050034 -58.224928 90)
			(size 0.519938 1.4986)
			(layers "F.Cu" "F.Mask" "F.Paste")
			(net "M_L_CPU0_SA_DQ<0>")
		)
		(pad "8" smd rect
			(at -2.050034 -57.375044 90)
			(size 0.519938 1.4986)
			(layers "F.Cu" "F.Mask" "F.Paste")
			(net "GND")
		)
		(pad "9" smd rect
			(at -2.050034 -56.524906 90)
			(size 0.519938 1.4986)
			(layers "F.Cu" "F.Mask" "F.Paste")
			(net "M_L_CPU0_SA_DQ<1>")
		)
		(pad "10" smd rect
			(at -2.050034 -55.675022 90)
			(size 0.519938 1.4986)
			(layers "F.Cu" "F.Mask" "F.Paste")
			(net "GND")
		)
		(pad "11" smd rect
			(at -2.050034 -54.824884 90)
			(size 0.519938 1.4986)
			(layers "F.Cu" "F.Mask" "F.Paste")
			(net "M_L_CPU0_SA_DQS_DP<0>")
		)
		(pad "12" smd rect
			(at -2.050034 -53.975 90)
			(size 0.519938 1.4986)
			(layers "F.Cu" "F.Mask" "F.Paste")
			(net "M_L_CPU0_SA_DQS_DN<0>")
		)
		(pad "13" smd rect
			(at -2.050034 -53.125116 90)
			(size 0.519938 1.4986)
			(layers "F.Cu" "F.Mask" "F.Paste")
			(net "GND")
		)
		(pad "14" smd rect
			(at -2.050034 -52.274978 90)
			(size 0.519938 1.4986)
			(layers "F.Cu" "F.Mask" "F.Paste")
			(net "M_L_CPU0_SA_DQ<4>")
		)
		(pad "15" smd rect
			(at -2.050034 -51.425094 90)
			(size 0.519938 1.4986)
			(layers "F.Cu" "F.Mask" "F.Paste")
			(net "GND")
		)
		(pad "16" smd rect
			(at -2.050034 -50.574956 90)
			(size 0.519938 1.4986)
			(layers "F.Cu" "F.Mask" "F.Paste")
			(net "M_L_CPU0_SA_DQ<5>")
		)
		(pad "17" smd rect
			(at -2.050034 -49.725072 90)
			(size 0.519938 1.4986)
			(layers "F.Cu" "F.Mask" "F.Paste")
			(net "GND")
		)
		(pad "18" smd rect
			(at -2.050034 -48.874934 90)
			(size 0.519938 1.4986)
			(layers "F.Cu" "F.Mask" "F.Paste")
			(net "M_L_CPU0_SA_DQ<8>")
		)
		(pad "19" smd rect
			(at -2.050034 -48.02505 90)
			(size 0.519938 1.4986)
			(layers "F.Cu" "F.Mask" "F.Paste")
			(net "GND")
		)
		(pad "20" smd rect
			(at -2.050034 -47.174912 90)
			(size 0.519938 1.4986)
			(layers "F.Cu" "F.Mask" "F.Paste")
			(net "M_L_CPU0_SA_DQ<9>")
		)
		(pad "21" smd rect
			(at -2.050034 -46.325028 90)
			(size 0.519938 1.4986)
			(layers "F.Cu" "F.Mask" "F.Paste")
			(net "GND")
		)
		(pad "22" smd rect
			(at -2.050034 -45.47489 90)
			(size 0.519938 1.4986)
			(layers "F.Cu" "F.Mask" "F.Paste")
			(net "M_L_CPU0_SA_DQS_DP<1>")
		)
		(pad "23" smd rect
			(at -2.050034 -44.625006 90)
			(size 0.519938 1.4986)
			(layers "F.Cu" "F.Mask" "F.Paste")
			(net "M_L_CPU0_SA_DQS_DN<1>")
		)
		(pad "24" smd rect
			(at -2.050034 -43.775122 90)
			(size 0.519938 1.4986)
			(layers "F.Cu" "F.Mask" "F.Paste")
			(net "GND")
		)
		(pad "25" smd rect
			(at -2.050034 -42.924984 90)
			(size 0.519938 1.4986)
			(layers "F.Cu" "F.Mask" "F.Paste")
			(net "M_L_CPU0_SA_DQ<12>")
		)
		(pad "26" smd rect
			(at -2.050034 -42.0751 90)
			(size 0.519938 1.4986)
			(layers "F.Cu" "F.Mask" "F.Paste")
			(net "GND")
		)
		(pad "27" smd rect
			(at -2.050034 -41.224962 90)
			(size 0.519938 1.4986)
			(layers "F.Cu" "F.Mask" "F.Paste")
			(net "M_L_CPU0_SA_DQ<13>")
		)
		(pad "28" smd rect
			(at -2.050034 -40.375078 90)
			(size 0.519938 1.4986)
			(layers "F.Cu" "F.Mask" "F.Paste")
			(net "GND")
		)
		(pad "29" smd rect
			(at -2.050034 -39.52494 90)
			(size 0.519938 1.4986)
			(layers "F.Cu" "F.Mask" "F.Paste")
			(net "M_L_CPU0_SA_DQ<16>")
		)
		(pad "30" smd rect
			(at -2.050034 -38.675056 90)
			(size 0.519938 1.4986)
			(layers "F.Cu" "F.Mask" "F.Paste")
			(net "GND")
		)
		(pad "31" smd rect
			(at -2.050034 -37.824918 90)
			(size 0.519938 1.4986)
			(layers "F.Cu" "F.Mask" "F.Paste")
			(net "M_L_CPU0_SA_DQ<17>")
		)
		(pad "32" smd rect
			(at -2.050034 -36.975034 90)
			(size 0.519938 1.4986)
			(layers "F.Cu" "F.Mask" "F.Paste")
			(net "GND")
		)
		(pad "33" smd rect
			(at -2.050034 -36.124896 90)
			(size 0.519938 1.4986)
			(layers "F.Cu" "F.Mask" "F.Paste")
			(net "M_L_CPU0_SA_DQS_DP<2>")
		)
		(pad "34" smd rect
			(at -2.050034 -35.275012 90)
			(size 0.519938 1.4986)
			(layers "F.Cu" "F.Mask" "F.Paste")
			(net "M_L_CPU0_SA_DQS_DN<2>")
		)
		(pad "35" smd rect
			(at -2.050034 -34.425128 90)
			(size 0.519938 1.4986)
			(layers "F.Cu" "F.Mask" "F.Paste")
			(net "GND")
		)
		(pad "36" smd rect
			(at -2.050034 -33.57499 90)
			(size 0.519938 1.4986)
			(layers "F.Cu" "F.Mask" "F.Paste")
			(net "M_L_CPU0_SA_DQ<20>")
		)
		(pad "37" smd rect
			(at -2.050034 -32.725106 90)
			(size 0.519938 1.4986)
			(layers "F.Cu" "F.Mask" "F.Paste")
			(net "GND")
		)
		(pad "38" smd rect
			(at -2.050034 -31.874968 90)
			(size 0.519938 1.4986)
			(layers "F.Cu" "F.Mask" "F.Paste")
			(net "M_L_CPU0_SA_DQ<21>")
		)
		(pad "39" smd rect
			(at -2.050034 -31.025084 90)
			(size 0.519938 1.4986)
			(layers "F.Cu" "F.Mask" "F.Paste")
			(net "GND")
		)
		(pad "40" smd rect
			(at -2.050034 -30.174946 90)
			(size 0.519938 1.4986)
			(layers "F.Cu" "F.Mask" "F.Paste")
			(net "M_L_CPU0_SA_DQ<24>")
		)
		(pad "41" smd rect
			(at -2.050034 -29.325062 90)
			(size 0.519938 1.4986)
			(layers "F.Cu" "F.Mask" "F.Paste")
			(net "GND")
		)
		(pad "42" smd rect
			(at -2.050034 -28.474924 90)
			(size 0.519938 1.4986)
			(layers "F.Cu" "F.Mask" "F.Paste")
			(net "M_L_CPU0_SA_DQ<25>")
		)
		(pad "43" smd rect
			(at -2.050034 -27.62504 90)
			(size 0.519938 1.4986)
			(layers "F.Cu" "F.Mask" "F.Paste")
			(net "GND")
		)
		(pad "44" smd rect
			(at -2.050034 -26.774902 90)
			(size 0.519938 1.4986)
			(layers "F.Cu" "F.Mask" "F.Paste")
			(net "M_L_CPU0_SA_DQS_DP<3>")
		)
		(pad "45" smd rect
			(at -2.050034 -25.925018 90)
			(size 0.519938 1.4986)
			(layers "F.Cu" "F.Mask" "F.Paste")
			(net "M_L_CPU0_SA_DQS_DN<3>")
		)
		(pad "46" smd rect
			(at -2.050034 -25.07488 90)
			(size 0.519938 1.4986)
			(layers "F.Cu" "F.Mask" "F.Paste")
			(net "GND")
		)
		(pad "47" smd rect
			(at -2.050034 -24.224996 90)
			(size 0.519938 1.4986)
			(layers "F.Cu" "F.Mask" "F.Paste")
			(net "M_L_CPU0_SA_DQ<28>")
		)
		(pad "48" smd rect
			(at -2.050034 -23.375112 90)
			(size 0.519938 1.4986)
			(layers "F.Cu" "F.Mask" "F.Paste")
			(net "GND")
		)
		(pad "49" smd rect
			(at -2.050034 -22.524974 90)
			(size 0.519938 1.4986)
			(layers "F.Cu" "F.Mask" "F.Paste")
			(net "M_L_CPU0_SA_DQ<29>")
		)
		(pad "50" smd rect
			(at -2.050034 -21.67509 90)
			(size 0.519938 1.4986)
			(layers "F.Cu" "F.Mask" "F.Paste")
			(net "GND")
		)
		(pad "51" smd rect
			(at -2.050034 -20.824952 90)
			(size 0.519938 1.4986)
			(layers "F.Cu" "F.Mask" "F.Paste")
			(net "M_L_CPU0_SA_CB<0>")
		)
		(pad "52" smd rect
			(at -2.050034 -19.975068 90)
			(size 0.519938 1.4986)
			(layers "F.Cu" "F.Mask" "F.Paste")
			(net "GND")
		)
		(pad "53" smd rect
			(at -2.050034 -19.12493 90)
			(size 0.519938 1.4986)
			(layers "F.Cu" "F.Mask" "F.Paste")
			(net "M_L_CPU0_SA_CB<1>")
		)
		(pad "54" smd rect
			(at -2.050034 -18.275046 90)
			(size 0.519938 1.4986)
			(layers "F.Cu" "F.Mask" "F.Paste")
			(net "GND")
		)
		(pad "55" smd rect
			(at -2.050034 -17.424908 90)
			(size 0.519938 1.4986)
			(layers "F.Cu" "F.Mask" "F.Paste")
			(net "M_L_CPU0_SA_DQS_DP<4>")
		)
		(pad "56" smd rect
			(at -2.050034 -16.575024 90)
			(size 0.519938 1.4986)
			(layers "F.Cu" "F.Mask" "F.Paste")
			(net "M_L_CPU0_SA_DQS_DN<4>")
		)
		(pad "57" smd rect
			(at -2.050034 -15.724886 90)
			(size 0.519938 1.4986)
			(layers "F.Cu" "F.Mask" "F.Paste")
			(net "GND")
		)
		(pad "58" smd rect
			(at -2.050034 -14.875002 90)
			(size 0.519938 1.4986)
			(layers "F.Cu" "F.Mask" "F.Paste")
			(net "M_L_CPU0_SA_CB<4>")
		)
		(pad "59" smd rect
			(at -2.050034 -14.025118 90)
			(size 0.519938 1.4986)
			(layers "F.Cu" "F.Mask" "F.Paste")
			(net "GND")
		)
		(pad "60" smd rect
			(at -2.050034 -13.17498 90)
			(size 0.519938 1.4986)
			(layers "F.Cu" "F.Mask" "F.Paste")
			(net "M_L_CPU0_SA_CB<5>")
		)
		(pad "61" smd rect
			(at -2.050034 -12.325096 90)
			(size 0.519938 1.4986)
			(layers "F.Cu" "F.Mask" "F.Paste")
			(net "GND")
		)
		(pad "62" smd rect
			(at -2.050034 -11.474958 90)
			(size 0.519938 1.4986)
			(layers "F.Cu" "F.Mask" "F.Paste")
			(net "M_L_CPU0_ALERT_N")
		)
		(pad "63" smd rect
			(at -2.050034 -10.625074 90)
			(size 0.519938 1.4986)
			(layers "F.Cu" "F.Mask" "F.Paste")
			(net "GND")
		)
		(pad "64" smd rect
			(at -2.050034 -9.774936 90)
			(size 0.519938 1.4986)
			(layers "F.Cu" "F.Mask" "F.Paste")
			(net "M_L_CPU0_SA_CS_N<0>")
		)
		(pad "65" smd rect
			(at -2.050034 -8.925052 90)
			(size 0.519938 1.4986)
			(layers "F.Cu" "F.Mask" "F.Paste")
			(net "GND")
		)
		(pad "66" smd rect
			(at -2.050034 -8.074914 90)
			(size 0.519938 1.4986)
			(layers "F.Cu" "F.Mask" "F.Paste")
			(net "M_L_CPU0_SA_CA<0>")
		)
		(pad "67" smd rect
			(at -2.050034 -7.22503 90)
			(size 0.519938 1.4986)
			(layers "F.Cu" "F.Mask" "F.Paste")
			(net "GND")
		)
		(pad "68" smd rect
			(at -2.050034 -6.374892 90)
			(size 0.519938 1.4986)
			(layers "F.Cu" "F.Mask" "F.Paste")
			(net "M_L_CPU0_SA_CA<2>")
		)
		(pad "69" smd rect
			(at -2.050034 -5.525008 90)
			(size 0.519938 1.4986)
			(layers "F.Cu" "F.Mask" "F.Paste")
			(net "GND")
		)
		(pad "70" smd rect
			(at -2.050034 -4.675124 90)
			(size 0.519938 1.4986)
			(layers "F.Cu" "F.Mask" "F.Paste")
			(net "M_L_CPU0_SA_CA<4>")
		)
		(pad "71" smd rect
			(at -2.050034 -3.824986 90)
			(size 0.519938 1.4986)
			(layers "F.Cu" "F.Mask" "F.Paste")
			(net "GND")
		)
		(pad "72" smd rect
			(at -2.050034 -2.975102 90)
			(size 0.519938 1.4986)
			(layers "F.Cu" "F.Mask" "F.Paste")
			(net "M_L_CPU0_SA_CA<6>")
		)
		(pad "73" smd rect
			(at -2.050034 -2.124964 90)
			(size 0.519938 1.4986)
			(layers "F.Cu" "F.Mask" "F.Paste")
			(net "GND")
		)
		(pad "74" smd rect
			(at -2.050034 -1.27508 90)
			(size 0.519938 1.4986)
			(layers "F.Cu" "F.Mask" "F.Paste")
			(net "M_L_CPU0_SA_PAR")
		)
		(pad "75" smd rect
			(at -2.050034 -0.424942 90)
			(size 0.519938 1.4986)
			(layers "F.Cu" "F.Mask" "F.Paste")
			(net "GND")
		)
		(pad "76" smd rect
			(at -2.050034 5.525008 90)
			(size 0.519938 1.4986)
			(layers "F.Cu" "F.Mask" "F.Paste")
			(net "M_L_CPU0_SB_CA<0>")
		)
		(pad "77" smd rect
			(at -2.050034 6.374892 90)
			(size 0.519938 1.4986)
			(layers "F.Cu" "F.Mask" "F.Paste")
			(net "GND")
		)
		(pad "78" smd rect
			(at -2.050034 7.22503 90)
			(size 0.519938 1.4986)
			(layers "F.Cu" "F.Mask" "F.Paste")
			(net "M_L_CPU0_SB_CA<2>")
		)
		(pad "79" smd rect
			(at -2.050034 8.074914 90)
			(size 0.519938 1.4986)
			(layers "F.Cu" "F.Mask" "F.Paste")
			(net "GND")
		)
		(pad "80" smd rect
			(at -2.050034 8.925052 90)
			(size 0.519938 1.4986)
			(layers "F.Cu" "F.Mask" "F.Paste")
			(net "M_L_CPU0_SB_CA<4>")
		)
		(pad "81" smd rect
			(at -2.050034 9.774936 90)
			(size 0.519938 1.4986)
			(layers "F.Cu" "F.Mask" "F.Paste")
			(net "GND")
		)
		(pad "82" smd rect
			(at -2.050034 10.625074 90)
			(size 0.519938 1.4986)
			(layers "F.Cu" "F.Mask" "F.Paste")
			(net "M_L_CPU0_SB_CA<6>")
		)
		(pad "83" smd rect
			(at -2.050034 11.474958 90)
			(size 0.519938 1.4986)
			(layers "F.Cu" "F.Mask" "F.Paste")
			(net "GND")
		)
		(pad "84" smd rect
			(at -2.050034 12.325096 90)
			(size 0.519938 1.4986)
			(layers "F.Cu" "F.Mask" "F.Paste")
			(net "M_L_CPU0_SB_CS_N<0>")
		)
		(pad "85" smd rect
			(at -2.050034 13.17498 90)
			(size 0.519938 1.4986)
			(layers "F.Cu" "F.Mask" "F.Paste")
			(net "GND")
		)
		(pad "86" smd rect
			(at -2.050034 14.025118 90)
			(size 0.519938 1.4986)
			(layers "F.Cu" "F.Mask" "F.Paste")
			(net "M_L_CPU0_SA_RSP<0>")
		)
		(pad "87" smd rect
			(at -2.050034 14.875002 90)
			(size 0.519938 1.4986)
			(layers "F.Cu" "F.Mask" "F.Paste")
			(net "M_L_CPU0_SB_RSP<0>")
		)
		(pad "88" smd rect
			(at -2.050034 15.724886 90)
			(size 0.519938 1.4986)
			(layers "F.Cu" "F.Mask" "F.Paste")
			(net "GND")
		)
		(pad "89" smd rect
			(at -2.050034 16.575024 90)
			(size 0.519938 1.4986)
			(layers "F.Cu" "F.Mask" "F.Paste")
			(net "M_L_CPU0_SB_CB<4>")
		)
		(pad "90" smd rect
			(at -2.050034 17.424908 90)
			(size 0.519938 1.4986)
			(layers "F.Cu" "F.Mask" "F.Paste")
			(net "GND")
		)
		(pad "91" smd rect
			(at -2.050034 18.275046 90)
			(size 0.519938 1.4986)
			(layers "F.Cu" "F.Mask" "F.Paste")
			(net "M_L_CPU0_SB_CB<5>")
		)
		(pad "92" smd rect
			(at -2.050034 19.12493 90)
			(size 0.519938 1.4986)
			(layers "F.Cu" "F.Mask" "F.Paste")
			(net "GND")
		)
		(pad "93" smd rect
			(at -2.050034 19.975068 90)
			(size 0.519938 1.4986)
			(layers "F.Cu" "F.Mask" "F.Paste")
			(net "M_L_CPU0_SB_DQS_DP<9>")
		)
		(pad "94" smd rect
			(at -2.050034 20.824952 90)
			(size 0.519938 1.4986)
			(layers "F.Cu" "F.Mask" "F.Paste")
			(net "M_L_CPU0_SB_DQS_DN<9>")
		)
		(pad "95" smd rect
			(at -2.050034 21.67509 90)
			(size 0.519938 1.4986)
			(layers "F.Cu" "F.Mask" "F.Paste")
			(net "GND")
		)
		(pad "96" smd rect
			(at -2.050034 22.524974 90)
			(size 0.519938 1.4986)
			(layers "F.Cu" "F.Mask" "F.Paste")
			(net "M_L_CPU0_SB_CB<0>")
		)
		(pad "97" smd rect
			(at -2.050034 23.375112 90)
			(size 0.519938 1.4986)
			(layers "F.Cu" "F.Mask" "F.Paste")
			(net "GND")
		)
		(pad "98" smd rect
			(at -2.050034 24.224996 90)
			(size 0.519938 1.4986)
			(layers "F.Cu" "F.Mask" "F.Paste")
			(net "M_L_CPU0_SB_CB<1>")
		)
		(pad "99" smd rect
			(at -2.050034 25.07488 90)
			(size 0.519938 1.4986)
			(layers "F.Cu" "F.Mask" "F.Paste")
			(net "GND")
		)
		(pad "100" smd rect
			(at -2.050034 25.925018 90)
			(size 0.519938 1.4986)
			(layers "F.Cu" "F.Mask" "F.Paste")
			(net "M_L_CPU0_SB_DQ<0>")
		)
		(pad "101" smd rect
			(at -2.050034 26.774902 90)
			(size 0.519938 1.4986)
			(layers "F.Cu" "F.Mask" "F.Paste")
			(net "GND")
		)
		(pad "102" smd rect
			(at -2.050034 27.62504 90)
			(size 0.519938 1.4986)
			(layers "F.Cu" "F.Mask" "F.Paste")
			(net "M_L_CPU0_SB_DQ<1>")
		)
		(pad "103" smd rect
			(at -2.050034 28.474924 90)
			(size 0.519938 1.4986)
			(layers "F.Cu" "F.Mask" "F.Paste")
			(net "GND")
		)
		(pad "104" smd rect
			(at -2.050034 29.325062 90)
			(size 0.519938 1.4986)
			(layers "F.Cu" "F.Mask" "F.Paste")
			(net "M_L_CPU0_SB_DQS_DP<0>")
		)
		(pad "105" smd rect
			(at -2.050034 30.174946 90)
			(size 0.519938 1.4986)
			(layers "F.Cu" "F.Mask" "F.Paste")
			(net "M_L_CPU0_SB_DQS_DN<0>")
		)
		(pad "106" smd rect
			(at -2.050034 31.025084 90)
			(size 0.519938 1.4986)
			(layers "F.Cu" "F.Mask" "F.Paste")
			(net "GND")
		)
		(pad "107" smd rect
			(at -2.050034 31.874968 90)
			(size 0.519938 1.4986)
			(layers "F.Cu" "F.Mask" "F.Paste")
			(net "M_L_CPU0_SB_DQ<4>")
		)
		(pad "108" smd rect
			(at -2.050034 32.725106 90)
			(size 0.519938 1.4986)
			(layers "F.Cu" "F.Mask" "F.Paste")
			(net "GND")
		)
		(pad "109" smd rect
			(at -2.050034 33.57499 90)
			(size 0.519938 1.4986)
			(layers "F.Cu" "F.Mask" "F.Paste")
			(net "M_L_CPU0_SB_DQ<5>")
		)
		(pad "110" smd rect
			(at -2.050034 34.425128 90)
			(size 0.519938 1.4986)
			(layers "F.Cu" "F.Mask" "F.Paste")
			(net "GND")
		)
		(pad "111" smd rect
			(at -2.050034 35.275012 90)
			(size 0.519938 1.4986)
			(layers "F.Cu" "F.Mask" "F.Paste")
			(net "M_L_CPU0_SB_DQ<8>")
		)
		(pad "112" smd rect
			(at -2.050034 36.124896 90)
			(size 0.519938 1.4986)
			(layers "F.Cu" "F.Mask" "F.Paste")
			(net "GND")
		)
		(pad "113" smd rect
			(at -2.050034 36.975034 90)
			(size 0.519938 1.4986)
			(layers "F.Cu" "F.Mask" "F.Paste")
			(net "M_L_CPU0_SB_DQ<9>")
		)
	)
)
